# T6G (Grand Teton) — schematic netlist excerpt (pin names and nets, part order shuffled) for the footprints in the layout excerpt that follows; sources: Cadence DE-HDL packaged netlist, KiCad conversion of 04192023_DAF0TMB3IC0_F0TG_MB_C_brd_V02_OCP.brd

R122  Q_RES  0 5% CHIP  pkg 0402LF  page 207 : A = PWRGD_PVDD11_S3_P0 ; B = PWRGD_PVDD11_S3_P0_R
C6639  Q_CAP_DIFFBUS  DIFF BUS_0.22UF 6.3V 20% X6S  pkg C0201  page 319 : \1\ = P5E_CPU1_P0_TX_BUF_C_DP<5> ; \2\ = P5E_CPU1_P0_TX_BUF_DP<5>
R6786  Q_RES  1K 1% CHIP  pkg 0402LF  page 362 : A = P0V9_RETIMER_CPU0_EN0_R ; B = GND

(kicad_pcb
	(version 20260206)
	(generator "pcbnew")
	(generator_version "10.0")
	(general
		(thickness 1.6)
		(legacy_teardrops no)
	)
	(paper "A4")
	(title_block
		(title "04192023_DAF0TMB3IC0_F0TG_MB_C_brd_V02_OCP.brd")
		(comment 1 "Grand Teton / footprints 4093-4095 of 8354")
	)
	(layers
		(0 "F.Cu" signal "TOP")
		(4 "In1.Cu" signal "GND")
		(6 "In2.Cu" signal "IN1")
		(8 "In3.Cu" signal "GND1")
		(10 "In4.Cu" signal "IN2")
		(12 "In5.Cu" signal "GND2")
		(14 "In6.Cu" signal "IN3")
		(16 "In7.Cu" signal "GND3")
		(18 "In8.Cu" signal "VCC")
		(20 "In9.Cu" signal "VCC1")
		(22 "In10.Cu" signal "GND4")
		(24 "In11.Cu" signal "IN4")
		(26 "In12.Cu" signal "GND5")
		(28 "In13.Cu" signal "IN5")
		(30 "In14.Cu" signal "GND6")
		(32 "In15.Cu" signal "IN6")
		(34 "In16.Cu" signal "GND7")
		(2 "B.Cu" signal "BOTTOM")
		(9 "F.Adhes" user "F.Adhesive")
		(11 "B.Adhes" user "B.Adhesive")
		(13 "F.Paste" user "Package Geometry/Pastemask Top")
		(15 "B.Paste" user "Package Geometry/Pastemask Bottom")
		(5 "F.SilkS" user "Ref Des/Silkscreen Top")
		(7 "B.SilkS" user "Ref Des/Silkscreen Bottom")
		(1 "F.Mask" user "Board Geometry/Soldermask Top")
		(3 "B.Mask" user "Board Geometry/Soldermask Bottom")
		(17 "Dwgs.User" user "User.Drawings")
		(19 "Cmts.User" user "User.Comments")
		(21 "Eco1.User" user "User.Eco1")
		(23 "Eco2.User" user "User.Eco2")
		(25 "Edge.Cuts" user "Board Geometry/Outline")
		(27 "Margin" user)
		(31 "F.CrtYd" user "Package Geometry/Place Bound Top")
		(29 "B.CrtYd" user "Package Geometry/Place Bound Bottom")
		(35 "F.Fab" user "Ref Des/Assembly Top")
		(33 "B.Fab" user "Ref Des/Assembly Bottom")
	)
	(footprint ""
		(layer "F.Cu")
		(at 414.316418 -366.780064)
		(property "Reference" "R122"
			(at 0 0 0)
			(layer "F.SilkS")
			(hide yes)
			(effects
				(font
					(size 1.27 1.27)
				)
			)
		)
		(property "Value" ""
			(at 0 0 0)
			(layer "F.Fab")
			(effects
				(font
					(size 1.27 1.27)
				)
			)
		)
		(duplicate_pad_numbers_are_jumpers no)
		(fp_line
			(start -0.7874 -0.4064)
			(end 0.7874 -0.4064)
			(stroke
				(width 0.1524)
				(type default)
			)
			(layer "F.SilkS")
		)
		(fp_line
			(start -0.7874 0.4064)
			(end -0.7874 -0.4064)
			(stroke
				(width 0.1524)
				(type default)
			)
			(layer "F.SilkS")
		)
		(fp_line
			(start 0.7874 -0.4064)
			(end 0.7874 0.4064)
			(stroke
				(width 0.1524)
				(type default)
			)
			(layer "F.SilkS")
		)
		(fp_line
			(start 0.7874 0.4064)
			(end -0.7874 0.4064)
			(stroke
				(width 0.1524)
				(type default)
			)
			(layer "F.SilkS")
		)
		(fp_line
			(start -0.67945 -0.305054)
			(end -0.12065 -0.305054)
			(stroke
				(width 0.1)
				(type default)
			)
			(layer "F.Fab")
		)
		(fp_line
			(start -0.67945 0.3048)
			(end -0.67945 -0.305054)
			(stroke
				(width 0.1)
				(type default)
			)
			(layer "F.Fab")
		)
		(fp_line
			(start -0.12065 -0.305054)
			(end -0.12065 -0.2794)
			(stroke
				(width 0.1)
				(type default)
			)
			(layer "F.Fab")
		)
		(fp_line
			(start -0.12065 -0.2794)
			(end 0.12065 -0.2794)
			(stroke
				(width 0.1)
				(type default)
			)
			(layer "F.Fab")
		)
		(fp_line
			(start -0.12065 0.2794)
			(end -0.12065 0.3048)
			(stroke
				(width 0.1)
				(type default)
			)
			(layer "F.Fab")
		)
		(fp_line
			(start -0.12065 0.3048)
			(end -0.67945 0.3048)
			(stroke
				(width 0.1)
				(type default)
			)
			(layer "F.Fab")
		)
		(fp_line
			(start 0.120396 0.2794)
			(end -0.12065 0.2794)
			(stroke
				(width 0.1)
				(type default)
			)
			(layer "F.Fab")
		)
		(fp_line
			(start 0.120396 0.3048)
			(end 0.120396 0.2794)
			(stroke
				(width 0.1)
				(type default)
			)
			(layer "F.Fab")
		)
		(fp_line
			(start 0.12065 -0.3048)
			(end 0.67945 -0.3048)
			(stroke
				(width 0.1)
				(type default)
			)
			(layer "F.Fab")
		)
		(fp_line
			(start 0.12065 -0.2794)
			(end 0.12065 -0.3048)
			(stroke
				(width 0.1)
				(type default)
			)
			(layer "F.Fab")
		)
		(fp_line
			(start 0.67945 -0.3048)
			(end 0.67945 0.3048)
			(stroke
				(width 0.1)
				(type default)
			)
			(layer "F.Fab")
		)
		(fp_line
			(start 0.67945 0.3048)
			(end 0.120396 0.3048)
			(stroke
				(width 0.1)
				(type default)
			)
			(layer "F.Fab")
		)
		(pad "1" smd circle
			(at -0.40005 0)
			(size 0 0)
			(layers "F.Cu" "F.Mask" "F.Paste")
			(net "PWRGD_PVDD11_S3_P0")
		)
		(pad "2" smd circle
			(at 0.40005 0)
			(size 0 0)
			(layers "F.Cu" "F.Mask" "F.Paste")
			(net "PWRGD_PVDD11_S3_P0_R")
		)
	)
	(footprint ""
		(layer "F.Cu")
		(at 63.999364 -408.517344 -90)
		(property "Reference" "C6639"
			(at 0 0 270)
			(layer "F.SilkS")
			(hide yes)
			(effects
				(font
					(size 1.27 1.27)
				)
			)
		)
		(property "Value" ""
			(at 0 0 270)
			(layer "F.Fab")
			(effects
				(font
					(size 1.27 1.27)
				)
			)
		)
		(duplicate_pad_numbers_are_jumpers no)
		(fp_line
			(start -0.299974 0.150114)
			(end -0.299974 -0.150114)
			(stroke
				(width 0.1)
				(type default)
			)
			(layer "F.Fab")
		)
		(fp_line
			(start 0.299974 0.150114)
			(end -0.299974 0.150114)
			(stroke
				(width 0.1)
				(type default)
			)
			(layer "F.Fab")
		)
		(fp_line
			(start -0.299974 -0.150114)
			(end 0.299974 -0.150114)
			(stroke
				(width 0.1)
				(type default)
			)
			(layer "F.Fab")
		)
		(fp_line
			(start 0.299974 -0.150114)
			(end 0.299974 0.150114)
			(stroke
				(width 0.1)
				(type default)
			)
			(layer "F.Fab")
		)
		(pad "1" smd rect
			(at -0.2667 0 270)
			(size 0.3048 0.381)
			(layers "F.Cu" "F.Mask" "F.Paste")
			(net "P5E_CPU1_P0_TX_BUF_C_DP<5>")
		)
		(pad "2" smd rect
			(at 0.2667 0 270)
			(size 0.3048 0.381)
			(layers "F.Cu" "F.Mask" "F.Paste")
			(net "P5E_CPU1_P0_TX_BUF_DP<5>")
		)
	)
	(footprint ""
		(layer "F.Cu")
		(at 439.029602 -425.94911 180)
		(property "Reference" "R6786"
			(at 0 0 180)
			(layer "F.SilkS")
			(hide yes)
			(effects
				(font
					(size 1.27 1.27)
				)
			)
		)
		(property "Value" ""
			(at 0 0 180)
			(layer "F.Fab")
			(effects
				(font
					(size 1.27 1.27)
				)
			)
		)
		(duplicate_pad_numbers_are_jumpers no)
		(fp_line
			(start 0.7874 0.4064)
			(end -0.7874 0.4064)
			(stroke
				(width 0.1524)
				(type default)
			)
			(layer "F.SilkS")
		)
		(fp_line
			(start 0.7874 -0.4064)
			(end 0.7874 0.4064)
			(stroke
				(width 0.1524)
				(type default)
			)
			(layer "F.SilkS")
		)
		(fp_line
			(start -0.7874 0.4064)
			(end -0.7874 -0.4064)
			(stroke
				(width 0.1524)
				(type default)
			)
			(layer "F.SilkS")
		)
		(fp_line
			(start -0.7874 -0.4064)
			(end 0.7874 -0.4064)
			(stroke
				(width 0.1524)
				(type default)
			)
			(layer "F.SilkS")
		)
		(fp_line
			(start 0.67945 0.3048)
			(end 0.120396 0.3048)
			(stroke
				(width 0.1)
				(type default)
			)
			(layer "F.Fab")
		)
		(fp_line
			(start 0.67945 -0.3048)
			(end 0.67945 0.3048)
			(stroke
				(width 0.1)
				(type default)
			)
			(layer "F.Fab")
		)
		(fp_line
			(start 0.12065 -0.2794)
			(end 0.12065 -0.3048)
			(stroke
				(width 0.1)
				(type default)
			)
			(layer "F.Fab")
		)
		(fp_line
			(start 0.12065 -0.3048)
			(end 0.67945 -0.3048)
			(stroke
				(width 0.1)
				(type default)
			)
			(layer "F.Fab")
		)
		(fp_line
			(start 0.120396 0.3048)
			(end 0.120396 0.2794)
			(stroke
				(width 0.1)
				(type default)
			)
			(layer "F.Fab")
		)
		(fp_line
			(start 0.120396 0.2794)
			(end -0.12065 0.2794)
			(stroke
				(width 0.1)
				(type default)
			)
			(layer "F.Fab")
		)
		(fp_line
			(start -0.12065 0.3048)
			(end -0.67945 0.3048)
			(stroke
				(width 0.1)
				(type default)
			)
			(layer "F.Fab")
		)
		(fp_line
			(start -0.12065 0.2794)
			(end -0.12065 0.3048)
			(stroke
				(width 0.1)
				(type default)
			)
			(layer "F.Fab")
		)
		(fp_line
			(start -0.12065 -0.2794)
			(end 0.12065 -0.2794)
			(stroke
				(width 0.1)
				(type default)
			)
			(layer "F.Fab")
		)
		(fp_line
			(start -0.12065 -0.305054)
			(end -0.12065 -0.2794)
			(stroke
				(width 0.1)
				(type default)
			)
			(layer "F.Fab")
		)
		(fp_line
			(start -0.67945 0.3048)
			(end -0.67945 -0.305054)
			(stroke
				(width 0.1)
				(type default)
			)
			(layer "F.Fab")
		)
		(fp_line
			(start -0.67945 -0.305054)
			(end -0.12065 -0.305054)
			(stroke
				(width 0.1)
				(type default)
			)
			(layer "F.Fab")
		)
		(pad "1" smd circle
			(at -0.40005 0 180)
			(size 0 0)
			(layers "F.Cu" "F.Mask" "F.Paste")
			(net "P0V9_RETIMER_CPU0_EN0_R")
		)
		(pad "2" smd circle
			(at 0.40005 0 180)
			(size 0 0)
			(layers "F.Cu" "F.Mask" "F.Paste")
			(net "GND")
		)
	)
)
